(kicad_pcb
	(version 20211014)
	(generator pcbnew)
	(general
    (thickness 1.6)
  )
	(paper "A4")
	(title_block
    (title "SI test board")
    (rev "1.0.1")
    (company "Antmicro")
		(comment 9 "footprints 1-5 of 27")
	)
	(layers
    (0 "F.Cu" signal)
    (1 "In1.Cu" signal)
    (2 "In2.Cu" signal)
    (31 "B.Cu" signal)
    (32 "B.Adhes" user "B.Adhesive")
    (33 "F.Adhes" user "F.Adhesive")
    (34 "B.Paste" user)
    (35 "F.Paste" user)
    (36 "B.SilkS" user "B.Silkscreen")
    (37 "F.SilkS" user "F.Silkscreen")
    (38 "B.Mask" user)
    (39 "F.Mask" user)
    (40 "Dwgs.User" user "User.Drawings")
    (41 "Cmts.User" user "User.Comments")
    (42 "Eco1.User" user "User.Eco1")
    (43 "Eco2.User" user "User.Eco2")
    (44 "Edge.Cuts" user)
    (45 "Margin" user)
    (46 "B.CrtYd" user "B.Courtyard")
    (47 "F.CrtYd" user "F.Courtyard")
    (48 "B.Fab" user)
    (49 "F.Fab" user)
  )
	(footprint "si-simulation-test-board-footprints:RF_SMA_BoardEdge_RF2-143-T-17-50-G" (layer "F.Cu")
    (tedit 64FEFFC5)
    (at 146.68 137.6155 -90)
    (descr "RF SMA SMD board edge connector")
    (property "Author" "Antmicro")
    (property "License" "Apache-2.0")
    (property "MPN" "RF2-143-T-17-50-G")
    (property "Manufacturer" "ADAM TECH")
    (property "Sheetfile" "si-simulation-test-board.kicad_sch")
    (property "Sheetname" "")
    (attr smd)
    (fp_text reference "J17" (at -4.5 6.88) (layer "F.SilkS")
      (effects (font (size 0.7 0.7) (thickness 0.15)) (justify left bottom))
    )
    (fp_text value "Conn_SMA_RF2-143-T-17-50-G" (at 0 9.24 -90) (layer "F.Fab")
      (effects (font (size 0.7 0.7) (thickness 0.15)) (justify left bottom))
    )
    (fp_text user "Author: Antmicro" (at -4.5 11.24 -90) (layer "F.Fab") hide
      (effects (font (size 0.7 0.7) (thickness 0.15)) (justify left bottom))
    )
    (fp_text user "License: Apache-2.0" (at -4.5 12.44 -90) (layer "F.Fab") hide
      (effects (font (size 0.7 0.7) (thickness 0.15)) (justify left bottom))
    )
    (fp_text user "${REFERENCE}" (at -4.5 13.64 -90) (layer "F.Fab") hide
      (effects (font (size 0.7 0.7) (thickness 0.15)) (justify left bottom))
    )
    (fp_rect (start -3.995 -7.53) (end 3.995 7.53) (layer "B.CrtYd") (width 0.05) (fill none))
    (fp_rect (start -3.995 -7.53) (end 3.995 7.53) (layer "F.CrtYd") (width 0.05) (fill none))
    (fp_line (start 0.38 2.654) (end 0.375 6.455) (layer "F.Fab") (width 0.15))
    (fp_line (start -3.174 6.455) (end -3.174 1.504) (layer "F.Fab") (width 0.15))
    (fp_line (start 2.65 -6.375) (end 2.65 1.504) (layer "F.Fab") (width 0.15))
    (fp_line (start 0.375 6.455) (end -0.38 6.455) (layer "F.Fab") (width 0.15))
    (fp_line (start -2.375 6.455) (end -3.174 6.455) (layer "F.Fab") (width 0.15))
    (fp_line (start 3.174 6.455) (end 3.174 1.504) (layer "F.Fab") (width 0.15))
    (fp_line (start 2.375 6.455) (end 2.375 2.678) (layer "F.Fab") (width 0.15))
    (fp_line (start -0.38 2.654) (end -0.38 6.455) (layer "F.Fab") (width 0.15))
    (fp_line (start -2.375 2.678) (end -2.375 6.455) (layer "F.Fab") (width 0.15))
    (fp_line (start 3.174 1.504) (end -3.174 1.504) (layer "F.Fab") (width 0.15))
    (fp_line (start 3.174 6.455) (end 2.375 6.455) (layer "F.Fab") (width 0.15))
    (fp_line (start 2.65 -6.375) (end -2.65 -6.375) (layer "F.Fab") (width 0.15))
    (fp_line (start -2.65 -6.375) (end -2.65 1.504) (layer "F.Fab") (width 0.15))
    (fp_line (start 3.174 2.654) (end -3.15 2.654) (layer "F.Fab") (width 0.15))
    (pad "1" smd rect (at 0.007 4.955 270) (size 2.29 4.191) (layers "F.Cu" "F.Paste" "F.Mask")
      (net 9 "Net-(J15-Pad1)") (pinfunction "1") (pintype "passive"))
    (pad "2" smd rect (at 2.975 4.955 270) (size 1.45 4.191) (layers "B.Cu" "B.Paste" "B.Mask")
      (net 2 "GND") (pinfunction "2") (pintype "passive"))
    (pad "2" smd rect (at -2.975 4.955 270) (size 1.45 4.191) (layers "F.Cu" "F.Paste" "F.Mask")
      (net 2 "GND") (pinfunction "2") (pintype "passive"))
    (pad "2" smd rect (at 2.975 4.955 270) (size 1.45 4.191) (layers "F.Cu" "F.Paste" "F.Mask")
      (net 2 "GND") (pinfunction "2") (pintype "passive"))
    (pad "2" smd rect (at -2.975 4.955 270) (size 1.45 4.191) (layers "B.Cu" "B.Paste" "B.Mask")
      (net 2 "GND") (pinfunction "2") (pintype "passive"))
  )
	(footprint "si-simulation-test-board-footprints:RF_SMA_BoardEdge_RF2-143-T-17-50-G" (layer "F.Cu")
    (tedit 64FEFFC5)
    (at 146.68 86.0005 -90)
    (descr "RF SMA SMD board edge connector")
    (property "Author" "Antmicro")
    (property "License" "Apache-2.0")
    (property "MPN" "RF2-143-T-17-50-G")
    (property "Manufacturer" "ADAM TECH")
    (property "Sheetfile" "si-simulation-test-board.kicad_sch")
    (property "Sheetname" "")
    (attr smd)
    (fp_text reference "J8" (at -4.5 6.88) (layer "F.SilkS")
      (effects (font (size 0.7 0.7) (thickness 0.15)) (justify left bottom))
    )
    (fp_text value "Conn_SMA_RF2-143-T-17-50-G" (at 0 9.24 -90) (layer "F.Fab")
      (effects (font (size 0.7 0.7) (thickness 0.15)) (justify left bottom))
    )
    (fp_text user "${REFERENCE}" (at -4.5 13.64 -90) (layer "F.Fab") hide
      (effects (font (size 0.7 0.7) (thickness 0.15)) (justify left bottom))
    )
    (fp_text user "License: Apache-2.0" (at -4.5 12.44 -90) (layer "F.Fab") hide
      (effects (font (size 0.7 0.7) (thickness 0.15)) (justify left bottom))
    )
    (fp_text user "Author: Antmicro" (at -4.5 11.24 -90) (layer "F.Fab") hide
      (effects (font (size 0.7 0.7) (thickness 0.15)) (justify left bottom))
    )
    (fp_rect (start -3.995 -7.53) (end 3.995 7.53) (layer "B.CrtYd") (width 0.05) (fill none))
    (fp_rect (start -3.995 -7.53) (end 3.995 7.53) (layer "F.CrtYd") (width 0.05) (fill none))
    (fp_line (start -0.38 2.654) (end -0.38 6.455) (layer "F.Fab") (width 0.15))
    (fp_line (start 3.174 6.455) (end 2.375 6.455) (layer "F.Fab") (width 0.15))
    (fp_line (start 2.65 -6.375) (end 2.65 1.504) (layer "F.Fab") (width 0.15))
    (fp_line (start -2.375 2.678) (end -2.375 6.455) (layer "F.Fab") (width 0.15))
    (fp_line (start 3.174 6.455) (end 3.174 1.504) (layer "F.Fab") (width 0.15))
    (fp_line (start 2.375 6.455) (end 2.375 2.678) (layer "F.Fab") (width 0.15))
    (fp_line (start -3.174 6.455) (end -3.174 1.504) (layer "F.Fab") (width 0.15))
    (fp_line (start 0.375 6.455) (end -0.38 6.455) (layer "F.Fab") (width 0.15))
    (fp_line (start -2.65 -6.375) (end -2.65 1.504) (layer "F.Fab") (width 0.15))
    (fp_line (start 2.65 -6.375) (end -2.65 -6.375) (layer "F.Fab") (width 0.15))
    (fp_line (start 3.174 2.654) (end -3.15 2.654) (layer "F.Fab") (width 0.15))
    (fp_line (start -2.375 6.455) (end -3.174 6.455) (layer "F.Fab") (width 0.15))
    (fp_line (start 0.38 2.654) (end 0.375 6.455) (layer "F.Fab") (width 0.15))
    (fp_line (start 3.174 1.504) (end -3.174 1.504) (layer "F.Fab") (width 0.15))
    (pad "1" smd rect (at 0.007 4.955 270) (size 2.29 4.191) (layers "F.Cu" "F.Paste" "F.Mask")
      (net 5 "Net-(J7-Pad1)") (pinfunction "1") (pintype "passive"))
    (pad "2" smd rect (at 2.975 4.955 270) (size 1.45 4.191) (layers "B.Cu" "B.Paste" "B.Mask")
      (net 2 "GND") (pinfunction "2") (pintype "passive"))
    (pad "2" smd rect (at -2.975 4.955 270) (size 1.45 4.191) (layers "B.Cu" "B.Paste" "B.Mask")
      (net 2 "GND") (pinfunction "2") (pintype "passive"))
    (pad "2" smd rect (at -2.975 4.955 270) (size 1.45 4.191) (layers "F.Cu" "F.Paste" "F.Mask")
      (net 2 "GND") (pinfunction "2") (pintype "passive"))
    (pad "2" smd rect (at 2.975 4.955 270) (size 1.45 4.191) (layers "F.Cu" "F.Paste" "F.Mask")
      (net 2 "GND") (pinfunction "2") (pintype "passive"))
  )
	(footprint "si-simulation-test-board-footprints:RF_SMA_BoardEdge_RF2-143-T-17-50-G" (layer "F.Cu")
    (tedit 64FEFFC5)
    (at 146.78 127.6155 -90)
    (descr "RF SMA SMD board edge connector")
    (property "Author" "Antmicro")
    (property "License" "Apache-2.0")
    (property "MPN" "RF2-143-T-17-50-G")
    (property "Manufacturer" "ADAM TECH")
    (property "Sheetfile" "si-simulation-test-board.kicad_sch")
    (property "Sheetname" "")
    (attr smd)
    (fp_text reference "J20" (at -4.5 6.88) (layer "F.SilkS")
      (effects (font (size 0.7 0.7) (thickness 0.15)) (justify left bottom))
    )
    (fp_text value "Conn_SMA_RF2-143-T-17-50-G" (at 0 9.24 -90) (layer "F.Fab")
      (effects (font (size 0.7 0.7) (thickness 0.15)) (justify left bottom))
    )
    (fp_text user "${REFERENCE}" (at -4.5 13.64 -90) (layer "F.Fab") hide
      (effects (font (size 0.7 0.7) (thickness 0.15)) (justify left bottom))
    )
    (fp_text user "Author: Antmicro" (at -4.5 11.24 -90) (layer "F.Fab") hide
      (effects (font (size 0.7 0.7) (thickness 0.15)) (justify left bottom))
    )
    (fp_text user "License: Apache-2.0" (at -4.5 12.44 -90) (layer "F.Fab") hide
      (effects (font (size 0.7 0.7) (thickness 0.15)) (justify left bottom))
    )
    (fp_rect (start -3.995 -7.53) (end 3.995 7.53) (layer "B.CrtYd") (width 0.05) (fill none))
    (fp_rect (start -3.995 -7.53) (end 3.995 7.53) (layer "F.CrtYd") (width 0.05) (fill none))
    (fp_line (start 3.174 6.455) (end 2.375 6.455) (layer "F.Fab") (width 0.15))
    (fp_line (start -3.174 6.455) (end -3.174 1.504) (layer "F.Fab") (width 0.15))
    (fp_line (start 0.375 6.455) (end -0.38 6.455) (layer "F.Fab") (width 0.15))
    (fp_line (start -2.65 -6.375) (end -2.65 1.504) (layer "F.Fab") (width 0.15))
    (fp_line (start -0.38 2.654) (end -0.38 6.455) (layer "F.Fab") (width 0.15))
    (fp_line (start 3.174 1.504) (end -3.174 1.504) (layer "F.Fab") (width 0.15))
    (fp_line (start -2.375 2.678) (end -2.375 6.455) (layer "F.Fab") (width 0.15))
    (fp_line (start 0.38 2.654) (end 0.375 6.455) (layer "F.Fab") (width 0.15))
    (fp_line (start 2.375 6.455) (end 2.375 2.678) (layer "F.Fab") (width 0.15))
    (fp_line (start -2.375 6.455) (end -3.174 6.455) (layer "F.Fab") (width 0.15))
    (fp_line (start 3.174 2.654) (end -3.15 2.654) (layer "F.Fab") (width 0.15))
    (fp_line (start 3.174 6.455) (end 3.174 1.504) (layer "F.Fab") (width 0.15))
    (fp_line (start 2.65 -6.375) (end -2.65 -6.375) (layer "F.Fab") (width 0.15))
    (fp_line (start 2.65 -6.375) (end 2.65 1.504) (layer "F.Fab") (width 0.15))
    (pad "1" smd rect (at 0.007 4.955 270) (size 2.29 4.191) (layers "F.Cu" "F.Paste" "F.Mask")
      (net 2 "GND") (pinfunction "1") (pintype "passive"))
    (pad "2" smd rect (at -2.975 4.955 270) (size 1.45 4.191) (layers "F.Cu" "F.Paste" "F.Mask")
      (net 2 "GND") (pinfunction "2") (pintype "passive"))
    (pad "2" smd rect (at 2.975 4.955 270) (size 1.45 4.191) (layers "F.Cu" "F.Paste" "F.Mask")
      (net 2 "GND") (pinfunction "2") (pintype "passive"))
    (pad "2" smd rect (at -2.975 4.955 270) (size 1.45 4.191) (layers "B.Cu" "B.Paste" "B.Mask")
      (net 2 "GND") (pinfunction "2") (pintype "passive"))
    (pad "2" smd rect (at 2.975 4.955 270) (size 1.45 4.191) (layers "B.Cu" "B.Paste" "B.Mask")
      (net 2 "GND") (pinfunction "2") (pintype "passive"))
  )
	(footprint "si-simulation-test-board-footprints:RF_SMA_BoardEdge_RF2-143-T-17-50-G" (layer "F.Cu")
    (tedit 64FEFFC5)
    (at 146.68 117.3005 -90)
    (descr "RF SMA SMD board edge connector")
    (property "Author" "Antmicro")
    (property "License" "Apache-2.0")
    (property "MPN" "RF2-143-T-17-50-G")
    (property "Manufacturer" "ADAM TECH")
    (property "Sheetfile" "si-simulation-test-board.kicad_sch")
    (property "Sheetname" "")
    (attr smd)
    (fp_text reference "J14" (at -4.5 6.88) (layer "F.SilkS")
      (effects (font (size 0.7 0.7) (thickness 0.15)) (justify left bottom))
    )
    (fp_text value "Conn_SMA_RF2-143-T-17-50-G" (at 0 9.24 -90) (layer "F.Fab")
      (effects (font (size 0.7 0.7) (thickness 0.15)) (justify left bottom))
    )
    (fp_text user "License: Apache-2.0" (at -4.5 12.44 -90) (layer "F.Fab") hide
      (effects (font (size 0.7 0.7) (thickness 0.15)) (justify left bottom))
    )
    (fp_text user "${REFERENCE}" (at -4.5 13.64 -90) (layer "F.Fab") hide
      (effects (font (size 0.7 0.7) (thickness 0.15)) (justify left bottom))
    )
    (fp_text user "Author: Antmicro" (at -4.5 11.24 -90) (layer "F.Fab") hide
      (effects (font (size 0.7 0.7) (thickness 0.15)) (justify left bottom))
    )
    (fp_rect (start -3.995 -7.53) (end 3.995 7.53) (layer "B.CrtYd") (width 0.05) (fill none))
    (fp_rect (start -3.995 -7.53) (end 3.995 7.53) (layer "F.CrtYd") (width 0.05) (fill none))
    (fp_line (start 2.65 -6.375) (end -2.65 -6.375) (layer "F.Fab") (width 0.15))
    (fp_line (start -2.375 6.455) (end -3.174 6.455) (layer "F.Fab") (width 0.15))
    (fp_line (start 2.375 6.455) (end 2.375 2.678) (layer "F.Fab") (width 0.15))
    (fp_line (start 2.65 -6.375) (end 2.65 1.504) (layer "F.Fab") (width 0.15))
    (fp_line (start -0.38 2.654) (end -0.38 6.455) (layer "F.Fab") (width 0.15))
    (fp_line (start 3.174 6.455) (end 2.375 6.455) (layer "F.Fab") (width 0.15))
    (fp_line (start 3.174 2.654) (end -3.15 2.654) (layer "F.Fab") (width 0.15))
    (fp_line (start 0.375 6.455) (end -0.38 6.455) (layer "F.Fab") (width 0.15))
    (fp_line (start 3.174 6.455) (end 3.174 1.504) (layer "F.Fab") (width 0.15))
    (fp_line (start 3.174 1.504) (end -3.174 1.504) (layer "F.Fab") (width 0.15))
    (fp_line (start -2.375 2.678) (end -2.375 6.455) (layer "F.Fab") (width 0.15))
    (fp_line (start 0.38 2.654) (end 0.375 6.455) (layer "F.Fab") (width 0.15))
    (fp_line (start -2.65 -6.375) (end -2.65 1.504) (layer "F.Fab") (width 0.15))
    (fp_line (start -3.174 6.455) (end -3.174 1.504) (layer "F.Fab") (width 0.15))
    (pad "1" smd rect (at 0.007 4.955 270) (size 2.29 4.191) (layers "F.Cu" "F.Paste" "F.Mask")
      (net 8 "/DIFF_N") (pinfunction "1") (pintype "passive"))
    (pad "2" smd rect (at -2.975 4.955 270) (size 1.45 4.191) (layers "B.Cu" "B.Paste" "B.Mask")
      (net 2 "GND") (pinfunction "2") (pintype "passive"))
    (pad "2" smd rect (at -2.975 4.955 270) (size 1.45 4.191) (layers "F.Cu" "F.Paste" "F.Mask")
      (net 2 "GND") (pinfunction "2") (pintype "passive"))
    (pad "2" smd rect (at 2.975 4.955 270) (size 1.45 4.191) (layers "B.Cu" "B.Paste" "B.Mask")
      (net 2 "GND") (pinfunction "2") (pintype "passive"))
    (pad "2" smd rect (at 2.975 4.955 270) (size 1.45 4.191) (layers "F.Cu" "F.Paste" "F.Mask")
      (net 2 "GND") (pinfunction "2") (pintype "passive"))
  )
	(footprint "si-simulation-test-board-footprints:RF_SMA_BoardEdge_RF2-143-T-17-50-G" (layer "F.Cu")
    (tedit 64FEFFC5)
    (at 91.37 95.999499 90)
    (descr "RF SMA SMD board edge connector")
    (property "Author" "Antmicro")
    (property "License" "Apache-2.0")
    (property "MPN" "RF2-143-T-17-50-G")
    (property "Manufacturer" "ADAM TECH")
    (property "Sheetfile" "si-simulation-test-board.kicad_sch")
    (property "Sheetname" "")
    (attr smd)
    (fp_text reference "J9" (at -4.5 6.88 180) (layer "F.SilkS")
      (effects (font (size 0.7 0.7) (thickness 0.15)) (justify left bottom))
    )
    (fp_text value "Conn_SMA_RF2-143-T-17-50-G" (at 0 9.24 90) (layer "F.Fab")
      (effects (font (size 0.7 0.7) (thickness 0.15)) (justify left bottom))
    )
    (fp_text user "License: Apache-2.0" (at -4.5 12.44 90) (layer "F.Fab") hide
      (effects (font (size 0.7 0.7) (thickness 0.15)) (justify left bottom))
    )
    (fp_text user "Author: Antmicro" (at -4.5 11.24 90) (layer "F.Fab") hide
      (effects (font (size 0.7 0.7) (thickness 0.15)) (justify left bottom))
    )
    (fp_text user "${REFERENCE}" (at -4.5 13.64 90) (layer "F.Fab") hide
      (effects (font (size 0.7 0.7) (thickness 0.15)) (justify left bottom))
    )
    (fp_rect (start -3.995 -7.53) (end 3.995 7.53) (layer "B.CrtYd") (width 0.05) (fill none))
    (fp_rect (start -3.995 -7.53) (end 3.995 7.53) (layer "F.CrtYd") (width 0.05) (fill none))
    (fp_line (start 0.375 6.455) (end -0.38 6.455) (layer "F.Fab") (width 0.15))
    (fp_line (start 2.65 -6.375) (end 2.65 1.504) (layer "F.Fab") (width 0.15))
    (fp_line (start -2.65 -6.375) (end -2.65 1.504) (layer "F.Fab") (width 0.15))
    (fp_line (start -3.174 6.455) (end -3.174 1.504) (layer "F.Fab") (width 0.15))
    (fp_line (start 2.375 6.455) (end 2.375 2.678) (layer "F.Fab") (width 0.15))
    (fp_line (start -0.38 2.654) (end -0.38 6.455) (layer "F.Fab") (width 0.15))
    (fp_line (start 3.174 1.504) (end -3.174 1.504) (layer "F.Fab") (width 0.15))
    (fp_line (start 3.174 6.455) (end 3.174 1.504) (layer "F.Fab") (width 0.15))
    (fp_line (start -2.375 2.678) (end -2.375 6.455) (layer "F.Fab") (width 0.15))
    (fp_line (start 3.174 6.455) (end 2.375 6.455) (layer "F.Fab") (width 0.15))
    (fp_line (start 2.65 -6.375) (end -2.65 -6.375) (layer "F.Fab") (width 0.15))
    (fp_line (start 3.174 2.654) (end -3.15 2.654) (layer "F.Fab") (width 0.15))
    (fp_line (start -2.375 6.455) (end -3.174 6.455) (layer "F.Fab") (width 0.15))
    (fp_line (start 0.38 2.654) (end 0.375 6.455) (layer "F.Fab") (width 0.15))
    (pad "1" smd rect (at 0.007 4.955 90) (size 2.29 4.191) (layers "F.Cu" "F.Paste" "F.Mask")
      (net 6 "Net-(J10-Pad1)") (pinfunction "1") (pintype "passive"))
    (pad "2" smd rect (at -2.975 4.955 90) (size 1.45 4.191) (layers "B.Cu" "B.Paste" "B.Mask")
      (net 2 "GND") (pinfunction "2") (pintype "passive"))
    (pad "2" smd rect (at 2.975 4.955 90) (size 1.45 4.191) (layers "B.Cu" "B.Paste" "B.Mask")
      (net 2 "GND") (pinfunction "2") (pintype "passive"))
    (pad "2" smd rect (at -2.975 4.955 90) (size 1.45 4.191) (layers "F.Cu" "F.Paste" "F.Mask")
      (net 2 "GND") (pinfunction "2") (pintype "passive"))
    (pad "2" smd rect (at 2.975 4.955 90) (size 1.45 4.191) (layers "F.Cu" "F.Paste" "F.Mask")
      (net 2 "GND") (pinfunction "2") (pintype "passive"))
  )
)
